# TIMECARD (Time Appliance Project (Time Card)) — schematic netlist excerpt (pin names and nets, part order shuffled) for the footprints in the layout excerpt that follows; sources: Cadence DE-HDL packaged netlist, KiCad conversion of R4006-B0001-02_R01.brd

C77  CAPACITOR  0.01UF 25V 10%  pkg SMC_0201R  page 28 : \1\ = SG ; \2\ = R_XP3R3V_PG
R12  RESISTOR  10KOHM 1%  pkg SMC_0402R_H016  page 27 : \1\ = XP12R0V_A_OV ; \2\ = SG

(kicad_pcb
	(version 20260206)
	(generator "pcbnew")
	(generator_version "10.0")
	(general
		(thickness 1.6)
		(legacy_teardrops no)
	)
	(paper "A4")
	(title_block
		(title "timecard-production-celestica-r4006 — R4006-B0001-02_R01.brd")
		(comment 1 "Time Appliance Project (Time Card) / footprints 609-610 of 1113")
	)
	(layers
		(0 "F.Cu" signal "TOP")
		(4 "In1.Cu" signal "L02_GND1")
		(6 "In2.Cu" signal "L03_SIG1")
		(8 "In3.Cu" signal "L04_GND2")
		(10 "In4.Cu" signal "L05_VCC1")
		(12 "In5.Cu" signal "L06_VCC2")
		(14 "In6.Cu" signal "L07_GND3")
		(16 "In7.Cu" signal "L08_SIG2")
		(18 "In8.Cu" signal "L09_GND4")
		(2 "B.Cu" signal "BOTTOM")
		(9 "F.Adhes" user "F.Adhesive")
		(11 "B.Adhes" user "B.Adhesive")
		(13 "F.Paste" user "Package Geometry/Pastemask Top")
		(15 "B.Paste" user "Package Geometry/Pastemask Bottom")
		(5 "F.SilkS" user "Ref Des/Silkscreen Top")
		(7 "B.SilkS" user "Ref Des/Silkscreen Bottom")
		(1 "F.Mask" user "Board Geometry/Soldermask Top")
		(3 "B.Mask" user "Board Geometry/Soldermask Bottom")
		(17 "Dwgs.User" user "User.Drawings")
		(19 "Cmts.User" user "User.Comments")
		(21 "Eco1.User" user "User.Eco1")
		(23 "Eco2.User" user "User.Eco2")
		(25 "Edge.Cuts" user "Board Geometry/Outline")
		(27 "Margin" user)
		(31 "F.CrtYd" user "Package Geometry/Place Bound Top")
		(29 "B.CrtYd" user "Package Geometry/Place Bound Bottom")
		(35 "F.Fab" user "Ref Des/Assembly Top")
		(33 "B.Fab" user "Ref Des/Assembly Bottom")
	)
	(footprint ""
		(layer "F.Cu")
		(at 139.329922 -100.7618 180)
		(property "Reference" "R12"
			(at 1.153922 1.05283 0)
			(unlocked yes)
			(layer "F.SilkS")
			(effects
				(font
					(size 0.7874 0.5842)
					(thickness 0.1524)
				)
			)
		)
		(property "Value" "VAL*"
			(at 0.02032 2.13233 180)
			(unlocked yes)
			(layer "F.Fab")
			(hide yes)
			(effects
				(font
					(size 0.7874 0.5842)
					(thickness 0.1524)
				)
			)
		)
		(property "Device Type" "RESISTOR-G155-11002-01,10KOHM,A"
			(at 0.008382 1.210564 180)
			(unlocked yes)
			(layer "F.Fab")
			(hide yes)
			(effects
				(font
					(size 0.7874 0.5842)
					(thickness 0.1524)
				)
			)
		)
		(property "User Part Number" "PARTNUM*"
			(at 0.02032 4.024884 180)
			(unlocked yes)
			(layer "Cmts.User")
			(hide yes)
			(effects
				(font
					(size 0.7874 0.5842)
					(thickness 0.1524)
				)
			)
		)
		(property "Tolerance" "TOL*"
			(at 0.044704 3.05435 180)
			(unlocked yes)
			(layer "Cmts.User")
			(hide yes)
			(effects
				(font
					(size 0.7874 0.5842)
					(thickness 0.1524)
				)
			)
		)
		(duplicate_pad_numbers_are_jumpers no)
		(fp_line
			(start 1.143 0.5588)
			(end 1.143 -0.5588)
			(stroke
				(width 0.1)
				(type default)
			)
			(layer "F.SilkS")
		)
		(fp_line
			(start 1.143 -0.5588)
			(end -1.143 -0.5588)
			(stroke
				(width 0.1)
				(type default)
			)
			(layer "F.SilkS")
		)
		(fp_line
			(start -1.143 0.5588)
			(end 1.143 0.5588)
			(stroke
				(width 0.1)
				(type default)
			)
			(layer "F.SilkS")
		)
		(fp_line
			(start -1.143 -0.5588)
			(end -1.143 0.5588)
			(stroke
				(width 0.1)
				(type default)
			)
			(layer "F.SilkS")
		)
		(fp_rect
			(start -1.143 0.5588)
			(end 1.143 -0.5588)
			(stroke
				(width 0)
				(type default)
			)
			(fill no)
			(layer "F.CrtYd")
		)
		(fp_line
			(start 0.508 0.3048)
			(end 0.508 -0.3048)
			(stroke
				(width 0.1)
				(type default)
			)
			(layer "F.Fab")
		)
		(fp_line
			(start 0.508 -0.3048)
			(end -0.508 -0.3048)
			(stroke
				(width 0.1)
				(type default)
			)
			(layer "F.Fab")
		)
		(fp_line
			(start -0.508 0.3048)
			(end 0.508 0.3048)
			(stroke
				(width 0.1)
				(type default)
			)
			(layer "F.Fab")
		)
		(fp_line
			(start -0.508 -0.3048)
			(end -0.508 0.3048)
			(stroke
				(width 0.1)
				(type default)
			)
			(layer "F.Fab")
		)
		(pad "1" smd rect
			(at -0.5334 0 180)
			(size 0.7112 0.6096)
			(layers "F.Cu" "F.Mask" "F.Paste")
			(net "XP12R0V_A_OV")
		)
		(pad "2" smd rect
			(at 0.5334 0 180)
			(size 0.7112 0.6096)
			(layers "F.Cu" "F.Mask" "F.Paste")
			(net "SG")
		)
		(zone
			(layer "F.Cu")
			(hatch none 0.5)
			(connect_pads
				(clearance 0)
			)
			(min_thickness 0.25)
			(keepout
				(tracks allowed)
				(vias not_allowed)
				(pads allowed)
				(copperpour not_allowed)
				(footprints allowed)
			)
			(placement
				(enabled no)
				(sheetname "")
			)
			(fill
				(thermal_gap 0.5)
				(thermal_bridge_width 0.5)
				(island_removal_mode 0)
			)
			(polygon
				(pts
					(xy 139.406122 -101.0666) (xy 139.253722 -101.0666) (xy 139.253722 -100.457) (xy 139.406122 -100.457)
				)
			)
		)
	)
	(footprint ""
		(layer "F.Cu")
		(at 89.8398 -104.6734 180)
		(property "Reference" "C77"
			(at -1.7272 0.69723 0)
			(unlocked yes)
			(layer "F.SilkS")
			(effects
				(font
					(size 0.7874 0.5842)
					(thickness 0.1524)
				)
			)
		)
		(property "Value" "VAL*"
			(at 0.193548 2.13614 180)
			(unlocked yes)
			(layer "F.Fab")
			(hide yes)
			(effects
				(font
					(size 0.7874 0.5842)
					(thickness 0.1524)
				)
			)
		)
		(property "User Part Number" "PARTNUM*"
			(at 0.216154 4.185666 180)
			(unlocked yes)
			(layer "Cmts.User")
			(hide yes)
			(effects
				(font
					(size 0.7874 0.5842)
					(thickness 0.1524)
				)
			)
		)
		(property "Device Type" "CAPACITOR-G104-0B103-EK,0.01UFA"
			(at 0.184404 1.180592 180)
			(unlocked yes)
			(layer "F.Fab")
			(hide yes)
			(effects
				(font
					(size 0.7874 0.5842)
					(thickness 0.1524)
				)
			)
		)
		(property "Tolerance" "TOL*"
			(at 0.216154 3.1496 180)
			(unlocked yes)
			(layer "Cmts.User")
			(hide yes)
			(effects
				(font
					(size 0.7874 0.5842)
					(thickness 0.1524)
				)
			)
		)
		(duplicate_pad_numbers_are_jumpers no)
		(fp_line
			(start 0.671322 0.4445)
			(end -0.671322 0.4445)
			(stroke
				(width 0.1)
				(type default)
			)
			(layer "F.SilkS")
		)
		(fp_line
			(start 0.671322 -0.4445)
			(end 0.671322 0.4445)
			(stroke
				(width 0.1)
				(type default)
			)
			(layer "F.SilkS")
		)
		(fp_line
			(start -0.671322 0.4445)
			(end -0.671322 -0.4445)
			(stroke
				(width 0.1)
				(type default)
			)
			(layer "F.SilkS")
		)
		(fp_line
			(start -0.671322 -0.4445)
			(end 0.671322 -0.4445)
			(stroke
				(width 0.1)
				(type default)
			)
			(layer "F.SilkS")
		)
		(fp_rect
			(start 0.671322 -0.4445)
			(end -0.671322 0.4445)
			(stroke
				(width 0)
				(type default)
			)
			(fill no)
			(layer "F.CrtYd")
		)
		(fp_line
			(start 0.31496 0.1651)
			(end 0.31496 -0.1651)
			(stroke
				(width 0.1)
				(type default)
			)
			(layer "F.Fab")
		)
		(fp_line
			(start 0.31496 -0.1651)
			(end -0.31496 -0.1651)
			(stroke
				(width 0.1)
				(type default)
			)
			(layer "F.Fab")
		)
		(fp_line
			(start -0.31496 0.1651)
			(end 0.31496 0.1651)
			(stroke
				(width 0.1)
				(type default)
			)
			(layer "F.Fab")
		)
		(fp_line
			(start -0.31496 -0.1651)
			(end -0.31496 0.1651)
			(stroke
				(width 0.1)
				(type default)
			)
			(layer "F.Fab")
		)
		(pad "1" smd rect
			(at -0.264922 0 180)
			(size 0.3048 0.381)
			(layers "F.Cu" "F.Mask" "F.Paste")
			(net "SG")
		)
		(pad "2" smd rect
			(at 0.264922 0 180)
			(size 0.3048 0.381)
			(layers "F.Cu" "F.Mask" "F.Paste")
			(net "R_XP3R3V_PG")
		)
		(zone
			(layer "F.Cu")
			(hatch none 0.5)
			(connect_pads
				(clearance 0)
			)
			(min_thickness 0.25)
			(keepout
				(tracks allowed)
				(vias not_allowed)
				(pads allowed)
				(copperpour not_allowed)
				(footprints allowed)
			)
			(placement
				(enabled no)
				(sheetname "")
			)
			(fill
				(thermal_gap 0.5)
				(thermal_bridge_width 0.5)
				(island_removal_mode 0)
			)
			(polygon
				(pts
					(xy 89.727278 -104.4829) (xy 89.952322 -104.4829) (xy 89.952322 -104.8639) (xy 89.727278 -104.8639)
				)
			)
		)
	)
)
